(kicad_pcb
	(version 20260206)
	(generator "pcbnew")
	(generator_version "10.0")
	(general
		(thickness 1.6)
		(legacy_teardrops no)
	)
	(paper "A4")
	(title_block
		(title "04192023_DAF0TMB3IC0_F0TG_MB_C_brd_V02_OCP.brd")
		(comment 1 "Grand Teton / footprints 826-826 of 8354")
	)
	(layers
		(0 "F.Cu" signal "TOP")
		(4 "In1.Cu" signal "GND")
		(6 "In2.Cu" signal "IN1")
		(8 "In3.Cu" signal "GND1")
		(10 "In4.Cu" signal "IN2")
		(12 "In5.Cu" signal "GND2")
		(14 "In6.Cu" signal "IN3")
		(16 "In7.Cu" signal "GND3")
		(18 "In8.Cu" signal "VCC")
		(20 "In9.Cu" signal "VCC1")
		(22 "In10.Cu" signal "GND4")
		(24 "In11.Cu" signal "IN4")
		(26 "In12.Cu" signal "GND5")
		(28 "In13.Cu" signal "IN5")
		(30 "In14.Cu" signal "GND6")
		(32 "In15.Cu" signal "IN6")
		(34 "In16.Cu" signal "GND7")
		(2 "B.Cu" signal "BOTTOM")
		(9 "F.Adhes" user "F.Adhesive")
		(11 "B.Adhes" user "B.Adhesive")
		(13 "F.Paste" user "Package Geometry/Pastemask Top")
		(15 "B.Paste" user "Package Geometry/Pastemask Bottom")
		(5 "F.SilkS" user "Ref Des/Silkscreen Top")
		(7 "B.SilkS" user "Ref Des/Silkscreen Bottom")
		(1 "F.Mask" user "Board Geometry/Soldermask Top")
		(3 "B.Mask" user "Board Geometry/Soldermask Bottom")
		(17 "Dwgs.User" user "User.Drawings")
		(19 "Cmts.User" user "User.Comments")
		(21 "Eco1.User" user "User.Eco1")
		(23 "Eco2.User" user "User.Eco2")
		(25 "Edge.Cuts" user "Board Geometry/Outline")
		(27 "Margin" user)
		(31 "F.CrtYd" user "Package Geometry/Place Bound Top")
		(29 "B.CrtYd" user "Package Geometry/Place Bound Bottom")
		(35 "F.Fab" user "Ref Des/Assembly Top")
		(33 "B.Fab" user "Ref Des/Assembly Bottom")
	)
	(footprint ""
		(layer "F.Cu")
		(at 48.82134 -346.87129 -90)
		(property "Reference" "PC441_2"
			(at 0 0 270)
			(layer "F.SilkS")
			(hide yes)
			(effects
				(font
					(size 1.27 1.27)
				)
			)
		)
		(property "Value" ""
			(at 0 0 270)
			(layer "F.Fab")
			(effects
				(font
					(size 1.27 1.27)
				)
			)
		)
		(duplicate_pad_numbers_are_jumpers no)
		(fp_line
			(start -0.7874 0.4064)
			(end -0.7874 -0.4064)
			(stroke
				(width 0.1524)
				(type default)
			)
			(layer "F.SilkS")
		)
		(fp_line
			(start 0.7874 0.4064)
			(end -0.7874 0.4064)
			(stroke
				(width 0.1524)
				(type default)
			)
			(layer "F.SilkS")
		)
		(fp_line
			(start -0.7874 -0.4064)
			(end 0.7874 -0.4064)
			(stroke
				(width 0.1524)
				(type default)
			)
			(layer "F.SilkS")
		)
		(fp_line
			(start 0.7874 -0.4064)
			(end 0.7874 0.4064)
			(stroke
				(width 0.1524)
				(type default)
			)
			(layer "F.SilkS")
		)
		(fp_line
			(start -0.67945 0.3048)
			(end -0.67945 -0.305054)
			(stroke
				(width 0.1)
				(type default)
			)
			(layer "F.Fab")
		)
		(fp_line
			(start -0.12065 0.3048)
			(end -0.67945 0.3048)
			(stroke
				(width 0.1)
				(type default)
			)
			(layer "F.Fab")
		)
		(fp_line
			(start 0.120396 0.3048)
			(end 0.120396 0.2794)
			(stroke
				(width 0.1)
				(type default)
			)
			(layer "F.Fab")
		)
		(fp_line
			(start 0.67945 0.3048)
			(end 0.120396 0.3048)
			(stroke
				(width 0.1)
				(type default)
			)
			(layer "F.Fab")
		)
		(fp_line
			(start -0.12065 0.2794)
			(end -0.12065 0.3048)
			(stroke
				(width 0.1)
				(type default)
			)
			(layer "F.Fab")
		)
		(fp_line
			(start 0.120396 0.2794)
			(end -0.12065 0.2794)
			(stroke
				(width 0.1)
				(type default)
			)
			(layer "F.Fab")
		)
		(fp_line
			(start -0.12065 -0.2794)
			(end 0.12065 -0.2794)
			(stroke
				(width 0.1)
				(type default)
			)
			(layer "F.Fab")
		)
		(fp_line
			(start 0.12065 -0.2794)
			(end 0.12065 -0.3048)
			(stroke
				(width 0.1)
				(type default)
			)
			(layer "F.Fab")
		)
		(fp_line
			(start 0.12065 -0.3048)
			(end 0.67945 -0.3048)
			(stroke
				(width 0.1)
				(type default)
			)
			(layer "F.Fab")
		)
		(fp_line
			(start 0.67945 -0.3048)
			(end 0.67945 0.3048)
			(stroke
				(width 0.1)
				(type default)
			)
			(layer "F.Fab")
		)
		(fp_line
			(start -0.67945 -0.305054)
			(end -0.12065 -0.305054)
			(stroke
				(width 0.1)
				(type default)
			)
			(layer "F.Fab")
		)
		(fp_line
			(start -0.12065 -0.305054)
			(end -0.12065 -0.2794)
			(stroke
				(width 0.1)
				(type default)
			)
			(layer "F.Fab")
		)
		(pad "1" smd circle
			(at -0.40005 0 270)
			(size 0 0)
			(layers "F.Cu" "F.Mask" "F.Paste")
			(net "SW_P12V_AUX_PVDDIO_P1_FLT")
		)
		(pad "2" smd circle
			(at 0.40005 0 270)
			(size 0 0)
			(layers "F.Cu" "F.Mask" "F.Paste")
			(net "GND")
		)
	)
)
